(kicad_pcb
	(version 20260206)
	(generator "pcbnew")
	(generator_version "10.0")
	(general
		(thickness 1.6)
		(legacy_teardrops no)
	)
	(paper "A4")
	(title_block
		(title "netronome-mezz — pcbd0082-001_rev01_jul9_a.brd")
		(comment 1 "Open CloudServer (Microsoft) / footprints 222-224 of 714")
	)
	(layers
		(0 "F.Cu" signal "TOP")
		(4 "In1.Cu" signal "02_GND")
		(6 "In2.Cu" signal "03_SIG")
		(8 "In3.Cu" signal "04_SIG")
		(10 "In4.Cu" signal "05_GND")
		(12 "In5.Cu" signal "06_PWR1")
		(14 "In6.Cu" signal "07_SIG")
		(16 "In7.Cu" signal "08_SIG")
		(18 "In8.Cu" signal "09_GND")
		(2 "B.Cu" signal "BOTTOM")
		(9 "F.Adhes" user "F.Adhesive")
		(11 "B.Adhes" user "B.Adhesive")
		(13 "F.Paste" user "Package Geometry/Pastemask Top")
		(15 "B.Paste" user "Package Geometry/Pastemask Bottom")
		(5 "F.SilkS" user "Ref Des/Silkscreen Top")
		(7 "B.SilkS" user "Ref Des/Silkscreen Bottom")
		(1 "F.Mask" user "Board Geometry/Soldermask Top")
		(3 "B.Mask" user "Board Geometry/Soldermask Bottom")
		(17 "Dwgs.User" user "User.Drawings")
		(19 "Cmts.User" user "User.Comments")
		(21 "Eco1.User" user "User.Eco1")
		(23 "Eco2.User" user "User.Eco2")
		(25 "Edge.Cuts" user "Board Geometry/Outline")
		(27 "Margin" user)
		(31 "F.CrtYd" user "Package Geometry/Place Bound Top")
		(29 "B.CrtYd" user "Package Geometry/Place Bound Bottom")
		(35 "F.Fab" user "Ref Des/Assembly Top")
		(33 "B.Fab" user "Ref Des/Assembly Bottom")
		(45 "User.4" user "COMPVAL_TYPE_BOTTOM")
	)
	(footprint ""
		(layer "F.Cu")
		(at 80.250995 18.255996)
		(property "Reference" "V2_A-A10"
			(at 0 0 0)
			(layer "F.SilkS")
			(hide yes)
			(effects
				(font
					(size 1.27 1.27)
				)
			)
		)
		(property "Value" ""
			(at 0 0 0)
			(layer "F.Fab")
			(effects
				(font
					(size 1.27 1.27)
				)
			)
		)
		(duplicate_pad_numbers_are_jumpers no)
		(pad "1" thru_hole circle
			(at 0 0)
			(size 0.762 0.762)
			(drill 0.20574)
			(layers "*.Cu" "*.Mask")
			(remove_unused_layers no)
			(net "DDR0_32A_A10")
			(clearance 0.127)
			(thermal_gap 0.127)
			(padstack
				(mode front_inner_back)
				(layer "Inner"
					(shape circle)
					(size 0.4572 0.4572)
					(clearance 0.1143)
				)
				(layer "B.Cu"
					(shape circle)
					(size 0.4572 0.4572)
					(clearance 0.1143)
				)
			)
		)
	)
	(footprint ""
		(layer "F.Cu")
		(at 78.232 32.576414)
		(property "Reference" "C111"
			(at -0.60833 3.618586 90)
			(unlocked yes)
			(layer "F.SilkS")
			(effects
				(font
					(size 0.7874 0.5842)
					(thickness 0.127)
				)
				(justify left)
			)
		)
		(property "Value" "0.1UF"
			(at -0.091846 0.2921 90)
			(unlocked yes)
			(layer "F.Fab")
			(hide yes)
			(effects
				(font
					(size 0.7874 0.5842)
					(thickness 0.2032)
				)
				(justify left)
			)
		)
		(property "Device Type" "CAPC0073"
			(at -0.091846 0.2921 90)
			(unlocked yes)
			(layer "F.Fab")
			(hide yes)
			(effects
				(font
					(size 0.7874 0.5842)
					(thickness 0.2032)
				)
				(justify left)
			)
		)
		(duplicate_pad_numbers_are_jumpers no)
		(fp_poly
			(pts
				(xy 0.635 1.0668) (xy 0.635 -1.0668) (xy -0.635 -1.0668) (xy -0.635 1.0668)
			)
			(stroke
				(width 0)
				(type default)
			)
			(fill no)
			(layer "F.CrtYd")
		)
		(fp_line
			(start -0.254 -0.508)
			(end 0.254 -0.508)
			(stroke
				(width 0.0254)
				(type default)
			)
			(layer "F.Fab")
		)
		(fp_line
			(start -0.254 0.508)
			(end -0.254 -0.508)
			(stroke
				(width 0.0254)
				(type default)
			)
			(layer "F.Fab")
		)
		(fp_line
			(start 0.254 -0.508)
			(end 0.254 0.508)
			(stroke
				(width 0.0254)
				(type default)
			)
			(layer "F.Fab")
		)
		(fp_line
			(start 0.254 0.508)
			(end -0.254 0.508)
			(stroke
				(width 0.0254)
				(type default)
			)
			(layer "F.Fab")
		)
		(pad "1" smd rect
			(at 0 -0.4191)
			(size 0.508 0.5334)
			(layers "F.Cu" "F.Mask" "F.Paste")
			(net "DDR_VDDQ")
		)
		(pad "2" smd rect
			(at 0 0.4191)
			(size 0.508 0.5334)
			(layers "F.Cu" "F.Mask" "F.Paste")
			(net "DDR_VTT")
		)
		(zone
			(layer "F.Cu")
			(hatch none 0.5)
			(connect_pads
				(clearance 0)
			)
			(min_thickness 0.25)
			(keepout
				(tracks not_allowed)
				(vias allowed)
				(pads allowed)
				(copperpour not_allowed)
				(footprints allowed)
			)
			(placement
				(enabled no)
				(sheetname "")
			)
			(fill
				(thermal_gap 0.5)
				(thermal_bridge_width 0.5)
				(island_removal_mode 0)
			)
			(polygon
				(pts
					(xy 78.2574 32.551014) (xy 78.2574 32.601814) (xy 78.2066 32.601814) (xy 78.2066 32.551014)
				)
			)
		)
	)
	(footprint ""
		(layer "F.Cu")
		(at 84.250987 30.612994)
		(property "Reference" "V3_A-A08"
			(at 0 0 0)
			(layer "F.SilkS")
			(hide yes)
			(effects
				(font
					(size 1.27 1.27)
				)
			)
		)
		(property "Value" ""
			(at 0 0 0)
			(layer "F.Fab")
			(effects
				(font
					(size 1.27 1.27)
				)
			)
		)
		(duplicate_pad_numbers_are_jumpers no)
		(pad "1" thru_hole circle
			(at 0 0)
			(size 0.762 0.762)
			(drill 0.20574)
			(layers "*.Cu" "*.Mask")
			(remove_unused_layers no)
			(net "DDR0_32A_A8")
			(clearance 0.127)
			(thermal_gap 0.127)
			(padstack
				(mode front_inner_back)
				(layer "Inner"
					(shape circle)
					(size 0.4572 0.4572)
					(clearance 0.1143)
				)
				(layer "B.Cu"
					(shape circle)
					(size 0.4572 0.4572)
					(clearance 0.1143)
				)
			)
		)
	)
)
